(kicad_pcb
	(version 20221018)
	(generator pcbnew)
	(general
    (thickness 1.62)
  )
	(paper "A4")
	(title_block
    (title "ECP5 - Datacenter Secure Control Module (DC-SCM)")
    (date "2024-07-01")
    (rev "1.2.1")
		(comment 9 "footprints 434-442 of 506")
	)
	(layers
    (0 "F.Cu" signal)
    (1 "In1.Cu" power)
    (2 "In2.Cu" signal)
    (3 "In3.Cu" power)
    (4 "In4.Cu" power)
    (5 "In5.Cu" signal)
    (6 "In6.Cu" power)
    (31 "B.Cu" signal)
    (32 "B.Adhes" user "B.Adhesive")
    (33 "F.Adhes" user "F.Adhesive")
    (34 "B.Paste" user)
    (35 "F.Paste" user)
    (36 "B.SilkS" user "B.Silkscreen")
    (37 "F.SilkS" user "F.Silkscreen")
    (38 "B.Mask" user)
    (39 "F.Mask" user)
    (40 "Dwgs.User" user "User.Drawings")
    (41 "Cmts.User" user "User.Comments")
    (42 "Eco1.User" user "User.Eco1")
    (43 "Eco2.User" user "User.Eco2")
    (44 "Edge.Cuts" user)
    (45 "Margin" user)
    (46 "B.CrtYd" user "B.Courtyard")
    (47 "F.CrtYd" user "F.Courtyard")
    (48 "B.Fab" user)
    (49 "F.Fab" user)
  )
	(footprint "antmicro-footprints:R_0402_1005Metric" (layer "B.Cu")
    (at 90.649 147.0742)
    (descr "Resistor SMD 0402")
    (tags "resistor SMD 0402")
    (property "Author" "Antmicro")
    (property "License" "Apache-2.0")
    (property "MPN" "CR0402-FX-3573GLF")
    (property "Manufacturer" "Bourns")
    (property "Public" "False")
    (property "Sheetfile" "interfaces.kicad_sch")
    (property "Sheetname" "Interfaces")
    (property "Tolerance" "1%")
    (property "Val" "357k")
    (property "ki_description" "SMD Chip Resistor")
    (property "ki_keywords" "0402, SMT, RESISTOR, PASSIVE")
    (attr smd)
    (fp_text reference "R53" (at -2.2 -0.03) (layer "B.SilkS")
        (effects (font (size 0.7 0.7) (thickness 0.127)) (justify mirror))
    )
    (fp_text value "R_357k_0402" (at 0 -1.17) (layer "B.Fab")
        (effects (font (size 1 1) (thickness 0.15)) (justify mirror))
    )
    (fp_text user "Author: Antmicro" (at -0.95 -4.169 180) (layer "B.Fab") hide
        (effects (font (size 0.7 0.7) (thickness 0.15)) (justify left bottom mirror))
    )
    (fp_text user "${REFERENCE}" (at 0 0) (layer "B.Fab")
        (effects (font (size 0.25 0.25) (thickness 0.04)) (justify mirror))
    )
    (fp_text user "License: Apache-2.0" (at -0.95 -5.169 180) (layer "B.Fab") hide
        (effects (font (size 0.7 0.7) (thickness 0.15)) (justify left bottom mirror))
    )
    (fp_rect (start -0.925 0.47) (end 0.925 -0.47)
      (stroke (width 0.05) (type default)) (fill none) (layer "B.CrtYd"))
    (fp_rect (start -0.5 0.25) (end 0.5 -0.25)
      (stroke (width 0.15) (type solid)) (fill none) (layer "B.Fab"))
    (pad "1" smd roundrect (at -0.48 0) (size 0.59 0.64) (layers "B.Cu" "B.Paste" "B.Mask") (roundrect_rratio 0.25)
      (net 2 "VCC3V3") (pintype "passive"))
    (pad "2" smd roundrect (at 0.48 0) (size 0.59 0.64) (layers "B.Cu" "B.Paste" "B.Mask") (roundrect_rratio 0.25)
      (net 171 "I3C[2]_SDA_3V3") (pintype "passive"))
  )
	(footprint "antmicro-footprints:R_0402_1005Metric" (layer "B.Cu")
    (at 90.649 146.0742)
    (descr "Resistor SMD 0402")
    (tags "resistor SMD 0402")
    (property "Author" "Antmicro")
    (property "License" "Apache-2.0")
    (property "MPN" "CR0402-FX-3573GLF")
    (property "Manufacturer" "Bourns")
    (property "Public" "False")
    (property "Sheetfile" "interfaces.kicad_sch")
    (property "Sheetname" "Interfaces")
    (property "Tolerance" "1%")
    (property "Val" "357k")
    (property "ki_description" "SMD Chip Resistor")
    (property "ki_keywords" "0402, SMT, RESISTOR, PASSIVE")
    (attr smd)
    (fp_text reference "R54" (at -2.2 -0.03) (layer "B.SilkS")
        (effects (font (size 0.7 0.7) (thickness 0.127)) (justify mirror))
    )
    (fp_text value "R_357k_0402" (at 0 -1.17) (layer "B.Fab")
        (effects (font (size 1 1) (thickness 0.15)) (justify mirror))
    )
    (fp_text user "Author: Antmicro" (at -0.95 -4.169 180) (layer "B.Fab") hide
        (effects (font (size 0.7 0.7) (thickness 0.15)) (justify left bottom mirror))
    )
    (fp_text user "${REFERENCE}" (at 0 0) (layer "B.Fab")
        (effects (font (size 0.25 0.25) (thickness 0.04)) (justify mirror))
    )
    (fp_text user "License: Apache-2.0" (at -0.95 -5.169 180) (layer "B.Fab") hide
        (effects (font (size 0.7 0.7) (thickness 0.15)) (justify left bottom mirror))
    )
    (fp_rect (start -0.925 0.47) (end 0.925 -0.47)
      (stroke (width 0.05) (type default)) (fill none) (layer "B.CrtYd"))
    (fp_rect (start -0.5 0.25) (end 0.5 -0.25)
      (stroke (width 0.15) (type solid)) (fill none) (layer "B.Fab"))
    (pad "1" smd roundrect (at -0.48 0) (size 0.59 0.64) (layers "B.Cu" "B.Paste" "B.Mask") (roundrect_rratio 0.25)
      (net 2 "VCC3V3") (pintype "passive"))
    (pad "2" smd roundrect (at 0.48 0) (size 0.59 0.64) (layers "B.Cu" "B.Paste" "B.Mask") (roundrect_rratio 0.25)
      (net 172 "I3C[2]_SCL_3V3") (pintype "passive"))
  )
	(footprint "antmicro-footprints:R_0402_1005Metric" (layer "B.Cu")
    (at 90.649 149.0742)
    (descr "Resistor SMD 0402")
    (tags "resistor SMD 0402")
    (property "Author" "Antmicro")
    (property "License" "Apache-2.0")
    (property "MPN" "CR0402-FX-3573GLF")
    (property "Manufacturer" "Bourns")
    (property "Public" "False")
    (property "Sheetfile" "interfaces.kicad_sch")
    (property "Sheetname" "Interfaces")
    (property "Tolerance" "1%")
    (property "Val" "357k")
    (property "ki_description" "SMD Chip Resistor")
    (property "ki_keywords" "0402, SMT, RESISTOR, PASSIVE")
    (attr smd)
    (fp_text reference "R55" (at -2.2 -0.03) (layer "B.SilkS")
        (effects (font (size 0.7 0.7) (thickness 0.127)) (justify mirror))
    )
    (fp_text value "R_357k_0402" (at 0 -1.17) (layer "B.Fab")
        (effects (font (size 1 1) (thickness 0.15)) (justify mirror))
    )
    (fp_text user "License: Apache-2.0" (at -0.95 -5.169 180) (layer "B.Fab") hide
        (effects (font (size 0.7 0.7) (thickness 0.15)) (justify left bottom mirror))
    )
    (fp_text user "${REFERENCE}" (at 0 0) (layer "B.Fab")
        (effects (font (size 0.25 0.25) (thickness 0.04)) (justify mirror))
    )
    (fp_text user "Author: Antmicro" (at -0.95 -4.169 180) (layer "B.Fab") hide
        (effects (font (size 0.7 0.7) (thickness 0.15)) (justify left bottom mirror))
    )
    (fp_rect (start -0.925 0.47) (end 0.925 -0.47)
      (stroke (width 0.05) (type default)) (fill none) (layer "B.CrtYd"))
    (fp_rect (start -0.5 0.25) (end 0.5 -0.25)
      (stroke (width 0.15) (type solid)) (fill none) (layer "B.Fab"))
    (pad "1" smd roundrect (at -0.48 0) (size 0.59 0.64) (layers "B.Cu" "B.Paste" "B.Mask") (roundrect_rratio 0.25)
      (net 2 "VCC3V3") (pintype "passive"))
    (pad "2" smd roundrect (at 0.48 0) (size 0.59 0.64) (layers "B.Cu" "B.Paste" "B.Mask") (roundrect_rratio 0.25)
      (net 173 "I3C[3]_SDA_3V3") (pintype "passive"))
  )
	(footprint "antmicro-footprints:R_0402_1005Metric" (layer "B.Cu")
    (at 90.649 148.0742)
    (descr "Resistor SMD 0402")
    (tags "resistor SMD 0402")
    (property "Author" "Antmicro")
    (property "License" "Apache-2.0")
    (property "MPN" "CR0402-FX-3573GLF")
    (property "Manufacturer" "Bourns")
    (property "Public" "False")
    (property "Sheetfile" "interfaces.kicad_sch")
    (property "Sheetname" "Interfaces")
    (property "Tolerance" "1%")
    (property "Val" "357k")
    (property "ki_description" "SMD Chip Resistor")
    (property "ki_keywords" "0402, SMT, RESISTOR, PASSIVE")
    (attr smd)
    (fp_text reference "R56" (at -2.2 -0.03) (layer "B.SilkS")
        (effects (font (size 0.7 0.7) (thickness 0.127)) (justify mirror))
    )
    (fp_text value "R_357k_0402" (at 0 -1.17) (layer "B.Fab")
        (effects (font (size 1 1) (thickness 0.15)) (justify mirror))
    )
    (fp_text user "License: Apache-2.0" (at -0.95 -5.169 180) (layer "B.Fab") hide
        (effects (font (size 0.7 0.7) (thickness 0.15)) (justify left bottom mirror))
    )
    (fp_text user "${REFERENCE}" (at 0 0) (layer "B.Fab")
        (effects (font (size 0.25 0.25) (thickness 0.04)) (justify mirror))
    )
    (fp_text user "Author: Antmicro" (at -0.95 -4.169 180) (layer "B.Fab") hide
        (effects (font (size 0.7 0.7) (thickness 0.15)) (justify left bottom mirror))
    )
    (fp_rect (start -0.925 0.47) (end 0.925 -0.47)
      (stroke (width 0.05) (type default)) (fill none) (layer "B.CrtYd"))
    (fp_rect (start -0.5 0.25) (end 0.5 -0.25)
      (stroke (width 0.15) (type solid)) (fill none) (layer "B.Fab"))
    (pad "1" smd roundrect (at -0.48 0) (size 0.59 0.64) (layers "B.Cu" "B.Paste" "B.Mask") (roundrect_rratio 0.25)
      (net 2 "VCC3V3") (pintype "passive"))
    (pad "2" smd roundrect (at 0.48 0) (size 0.59 0.64) (layers "B.Cu" "B.Paste" "B.Mask") (roundrect_rratio 0.25)
      (net 174 "I3C[3]_SCL_3V3") (pintype "passive"))
  )
	(footprint "antmicro-footprints:C_0402_1005Metric" (layer "B.Cu")
    (at 85.8 94.6 180)
    (descr "Capacitor SMD 0402")
    (tags "capacitor SMD 0402")
    (property "Author" "Antmicro")
    (property "Dielectric" "X5R")
    (property "License" "Apache-2.0")
    (property "MPN" "GRM155R61H104KE14D")
    (property "Manufacturer" "Murata")
    (property "Public" "False")
    (property "Sheetfile" "interfaces.kicad_sch")
    (property "Sheetname" "Interfaces")
    (property "Val" "100n")
    (property "Voltage" "50V")
    (property "ki_description" "SMD Multilayer Ceramic Capacitor, 0.1 µF, 50 V, 0402 [1005 Metric], ± 10%, X5R, GRM Series")
    (property "ki_keywords" "0402, SMT, CAPACITOR, PASSIVE, CERAMIC, MLCC")
    (attr smd)
    (fp_text reference "C242" (at 0.066667 9.47) (layer "B.SilkS")
        (effects (font (size 0.7 0.7) (thickness 0.127)) (justify mirror))
    )
    (fp_text value "C_100n_0402" (at 0 -1.17) (layer "B.Fab")
        (effects (font (size 1 1) (thickness 0.15)) (justify mirror))
    )
    (fp_text user "License: Apache-2.0" (at -0.939 -5.799) (layer "B.Fab") hide
        (effects (font (size 0.7 0.7) (thickness 0.15)) (justify left bottom mirror))
    )
    (fp_text user "${REFERENCE}" (at 0 0) (layer "B.Fab")
        (effects (font (size 0.25 0.25) (thickness 0.04)) (justify mirror))
    )
    (fp_text user "Author: Antmicro" (at -0.939 -3.399) (layer "B.Fab") hide
        (effects (font (size 0.7 0.7) (thickness 0.15)) (justify left bottom mirror))
    )
    (fp_rect (start -0.925 0.47) (end 0.925 -0.47)
      (stroke (width 0.05) (type default)) (fill none) (layer "B.CrtYd"))
    (fp_line (start -0.494 -0.248) (end -0.494 0.25)
      (stroke (width 0.15) (type solid)) (layer "B.Fab"))
    (fp_line (start -0.494 0.25) (end 0.504 0.25)
      (stroke (width 0.15) (type solid)) (layer "B.Fab"))
    (fp_line (start 0.504 -0.248) (end -0.494 -0.248)
      (stroke (width 0.15) (type solid)) (layer "B.Fab"))
    (fp_line (start 0.504 0.25) (end 0.504 -0.248)
      (stroke (width 0.15) (type solid)) (layer "B.Fab"))
    (pad "1" smd roundrect (at -0.48 0 180) (size 0.59 0.64) (layers "B.Cu" "B.Paste" "B.Mask") (roundrect_rratio 0.25)
      (net 1 "GND") (pintype "passive"))
    (pad "2" smd roundrect (at 0.48 0 180) (size 0.59 0.64) (layers "B.Cu" "B.Paste" "B.Mask") (roundrect_rratio 0.25)
      (net 2 "VCC3V3") (pintype "passive"))
  )
	(footprint "antmicro-footprints:C_0402_1005Metric" (layer "B.Cu")
    (at 85.8 96.6 180)
    (descr "Capacitor SMD 0402")
    (tags "capacitor SMD 0402")
    (property "Author" "Antmicro")
    (property "Dielectric" "X5R")
    (property "License" "Apache-2.0")
    (property "MPN" "GRM155R61H104KE14D")
    (property "Manufacturer" "Murata")
    (property "Public" "False")
    (property "Sheetfile" "interfaces.kicad_sch")
    (property "Sheetname" "Interfaces")
    (property "Val" "100n")
    (property "Voltage" "50V")
    (property "ki_description" "SMD Multilayer Ceramic Capacitor, 0.1 µF, 50 V, 0402 [1005 Metric], ± 10%, X5R, GRM Series")
    (property "ki_keywords" "0402, SMT, CAPACITOR, PASSIVE, CERAMIC, MLCC")
    (attr smd)
    (fp_text reference "C243" (at 0.066667 9.3775) (layer "B.SilkS")
        (effects (font (size 0.7 0.7) (thickness 0.127)) (justify mirror))
    )
    (fp_text value "C_100n_0402" (at 0 -1.17) (layer "B.Fab")
        (effects (font (size 1 1) (thickness 0.15)) (justify mirror))
    )
    (fp_text user "License: Apache-2.0" (at -0.939 -5.799) (layer "B.Fab") hide
        (effects (font (size 0.7 0.7) (thickness 0.15)) (justify left bottom mirror))
    )
    (fp_text user "Author: Antmicro" (at -0.939 -3.399) (layer "B.Fab") hide
        (effects (font (size 0.7 0.7) (thickness 0.15)) (justify left bottom mirror))
    )
    (fp_text user "${REFERENCE}" (at 0 0) (layer "B.Fab")
        (effects (font (size 0.25 0.25) (thickness 0.04)) (justify mirror))
    )
    (fp_rect (start -0.925 0.47) (end 0.925 -0.47)
      (stroke (width 0.05) (type default)) (fill none) (layer "B.CrtYd"))
    (fp_line (start -0.494 -0.248) (end -0.494 0.25)
      (stroke (width 0.15) (type solid)) (layer "B.Fab"))
    (fp_line (start -0.494 0.25) (end 0.504 0.25)
      (stroke (width 0.15) (type solid)) (layer "B.Fab"))
    (fp_line (start 0.504 -0.248) (end -0.494 -0.248)
      (stroke (width 0.15) (type solid)) (layer "B.Fab"))
    (fp_line (start 0.504 0.25) (end 0.504 -0.248)
      (stroke (width 0.15) (type solid)) (layer "B.Fab"))
    (pad "1" smd roundrect (at -0.48 0 180) (size 0.59 0.64) (layers "B.Cu" "B.Paste" "B.Mask") (roundrect_rratio 0.25)
      (net 1 "GND") (pintype "passive"))
    (pad "2" smd roundrect (at 0.48 0 180) (size 0.59 0.64) (layers "B.Cu" "B.Paste" "B.Mask") (roundrect_rratio 0.25)
      (net 2 "VCC3V3") (pintype "passive"))
  )
	(footprint "antmicro-footprints:C_0402_1005Metric" (layer "B.Cu")
    (at 85.8 98.6 180)
    (descr "Capacitor SMD 0402")
    (tags "capacitor SMD 0402")
    (property "Author" "Antmicro")
    (property "Dielectric" "X5R")
    (property "License" "Apache-2.0")
    (property "MPN" "GRM155R61H104KE14D")
    (property "Manufacturer" "Murata")
    (property "Public" "False")
    (property "Sheetfile" "interfaces.kicad_sch")
    (property "Sheetname" "Interfaces")
    (property "Val" "100n")
    (property "Voltage" "50V")
    (property "ki_description" "SMD Multilayer Ceramic Capacitor, 0.1 µF, 50 V, 0402 [1005 Metric], ± 10%, X5R, GRM Series")
    (property "ki_keywords" "0402, SMT, CAPACITOR, PASSIVE, CERAMIC, MLCC")
    (attr smd)
    (fp_text reference "C244" (at 0.066667 9.285) (layer "B.SilkS")
        (effects (font (size 0.7 0.7) (thickness 0.127)) (justify mirror))
    )
    (fp_text value "C_100n_0402" (at 0 -1.17) (layer "B.Fab")
        (effects (font (size 1 1) (thickness 0.15)) (justify mirror))
    )
    (fp_text user "${REFERENCE}" (at 0 0) (layer "B.Fab")
        (effects (font (size 0.25 0.25) (thickness 0.04)) (justify mirror))
    )
    (fp_text user "License: Apache-2.0" (at -0.939 -5.799) (layer "B.Fab") hide
        (effects (font (size 0.7 0.7) (thickness 0.15)) (justify left bottom mirror))
    )
    (fp_text user "Author: Antmicro" (at -0.939 -3.399) (layer "B.Fab") hide
        (effects (font (size 0.7 0.7) (thickness 0.15)) (justify left bottom mirror))
    )
    (fp_rect (start -0.925 0.47) (end 0.925 -0.47)
      (stroke (width 0.05) (type default)) (fill none) (layer "B.CrtYd"))
    (fp_line (start -0.494 -0.248) (end -0.494 0.25)
      (stroke (width 0.15) (type solid)) (layer "B.Fab"))
    (fp_line (start -0.494 0.25) (end 0.504 0.25)
      (stroke (width 0.15) (type solid)) (layer "B.Fab"))
    (fp_line (start 0.504 -0.248) (end -0.494 -0.248)
      (stroke (width 0.15) (type solid)) (layer "B.Fab"))
    (fp_line (start 0.504 0.25) (end 0.504 -0.248)
      (stroke (width 0.15) (type solid)) (layer "B.Fab"))
    (pad "1" smd roundrect (at -0.48 0 180) (size 0.59 0.64) (layers "B.Cu" "B.Paste" "B.Mask") (roundrect_rratio 0.25)
      (net 1 "GND") (pintype "passive"))
    (pad "2" smd roundrect (at 0.48 0 180) (size 0.59 0.64) (layers "B.Cu" "B.Paste" "B.Mask") (roundrect_rratio 0.25)
      (net 2 "VCC3V3") (pintype "passive"))
  )
	(footprint "antmicro-footprints:C_0402_1005Metric" (layer "B.Cu")
    (at 85.8 99.6 180)
    (descr "Capacitor SMD 0402")
    (tags "capacitor SMD 0402")
    (property "Author" "Antmicro")
    (property "Dielectric" "X5R")
    (property "License" "Apache-2.0")
    (property "MPN" "GRM155R61H104KE14D")
    (property "Manufacturer" "Murata")
    (property "Public" "False")
    (property "Sheetfile" "interfaces.kicad_sch")
    (property "Sheetname" "Interfaces")
    (property "Val" "100n")
    (property "Voltage" "50V")
    (property "ki_description" "SMD Multilayer Ceramic Capacitor, 0.1 µF, 50 V, 0402 [1005 Metric], ± 10%, X5R, GRM Series")
    (property "ki_keywords" "0402, SMT, CAPACITOR, PASSIVE, CERAMIC, MLCC")
    (attr smd)
    (fp_text reference "C245" (at 0.066667 9.23875) (layer "B.SilkS")
        (effects (font (size 0.7 0.7) (thickness 0.127)) (justify mirror))
    )
    (fp_text value "C_100n_0402" (at 0 -1.17) (layer "B.Fab")
        (effects (font (size 1 1) (thickness 0.15)) (justify mirror))
    )
    (fp_text user "Author: Antmicro" (at -0.939 -3.399) (layer "B.Fab") hide
        (effects (font (size 0.7 0.7) (thickness 0.15)) (justify left bottom mirror))
    )
    (fp_text user "License: Apache-2.0" (at -0.939 -5.799) (layer "B.Fab") hide
        (effects (font (size 0.7 0.7) (thickness 0.15)) (justify left bottom mirror))
    )
    (fp_text user "${REFERENCE}" (at 0 0) (layer "B.Fab")
        (effects (font (size 0.25 0.25) (thickness 0.04)) (justify mirror))
    )
    (fp_rect (start -0.925 0.47) (end 0.925 -0.47)
      (stroke (width 0.05) (type default)) (fill none) (layer "B.CrtYd"))
    (fp_line (start -0.494 -0.248) (end -0.494 0.25)
      (stroke (width 0.15) (type solid)) (layer "B.Fab"))
    (fp_line (start -0.494 0.25) (end 0.504 0.25)
      (stroke (width 0.15) (type solid)) (layer "B.Fab"))
    (fp_line (start 0.504 -0.248) (end -0.494 -0.248)
      (stroke (width 0.15) (type solid)) (layer "B.Fab"))
    (fp_line (start 0.504 0.25) (end 0.504 -0.248)
      (stroke (width 0.15) (type solid)) (layer "B.Fab"))
    (pad "1" smd roundrect (at -0.48 0 180) (size 0.59 0.64) (layers "B.Cu" "B.Paste" "B.Mask") (roundrect_rratio 0.25)
      (net 1 "GND") (pintype "passive"))
    (pad "2" smd roundrect (at 0.48 0 180) (size 0.59 0.64) (layers "B.Cu" "B.Paste" "B.Mask") (roundrect_rratio 0.25)
      (net 2 "VCC3V3") (pintype "passive"))
  )
	(footprint "antmicro-footprints:C_0402_1005Metric" (layer "B.Cu")
    (at 85.8 100.6 180)
    (descr "Capacitor SMD 0402")
    (tags "capacitor SMD 0402")
    (property "Author" "Antmicro")
    (property "Dielectric" "X5R")
    (property "License" "Apache-2.0")
    (property "MPN" "GRM155R61H104KE14D")
    (property "Manufacturer" "Murata")
    (property "Public" "False")
    (property "Sheetfile" "interfaces.kicad_sch")
    (property "Sheetname" "Interfaces")
    (property "Val" "100n")
    (property "Voltage" "50V")
    (property "ki_description" "SMD Multilayer Ceramic Capacitor, 0.1 µF, 50 V, 0402 [1005 Metric], ± 10%, X5R, GRM Series")
    (property "ki_keywords" "0402, SMT, CAPACITOR, PASSIVE, CERAMIC, MLCC")
    (attr smd)
    (fp_text reference "C246" (at 0.066667 9.1925) (layer "B.SilkS")
        (effects (font (size 0.7 0.7) (thickness 0.127)) (justify mirror))
    )
    (fp_text value "C_100n_0402" (at 0 -1.17) (layer "B.Fab")
        (effects (font (size 1 1) (thickness 0.15)) (justify mirror))
    )
    (fp_text user "${REFERENCE}" (at 0 0) (layer "B.Fab")
        (effects (font (size 0.25 0.25) (thickness 0.04)) (justify mirror))
    )
    (fp_text user "License: Apache-2.0" (at -0.939 -5.799) (layer "B.Fab") hide
        (effects (font (size 0.7 0.7) (thickness 0.15)) (justify left bottom mirror))
    )
    (fp_text user "Author: Antmicro" (at -0.939 -3.399) (layer "B.Fab") hide
        (effects (font (size 0.7 0.7) (thickness 0.15)) (justify left bottom mirror))
    )
    (fp_rect (start -0.925 0.47) (end 0.925 -0.47)
      (stroke (width 0.05) (type default)) (fill none) (layer "B.CrtYd"))
    (fp_line (start -0.494 -0.248) (end -0.494 0.25)
      (stroke (width 0.15) (type solid)) (layer "B.Fab"))
    (fp_line (start -0.494 0.25) (end 0.504 0.25)
      (stroke (width 0.15) (type solid)) (layer "B.Fab"))
    (fp_line (start 0.504 -0.248) (end -0.494 -0.248)
      (stroke (width 0.15) (type solid)) (layer "B.Fab"))
    (fp_line (start 0.504 0.25) (end 0.504 -0.248)
      (stroke (width 0.15) (type solid)) (layer "B.Fab"))
    (pad "1" smd roundrect (at -0.48 0 180) (size 0.59 0.64) (layers "B.Cu" "B.Paste" "B.Mask") (roundrect_rratio 0.25)
      (net 1 "GND") (pintype "passive"))
    (pad "2" smd roundrect (at 0.48 0 180) (size 0.59 0.64) (layers "B.Cu" "B.Paste" "B.Mask") (roundrect_rratio 0.25)
      (net 2 "VCC3V3") (pintype "passive"))
  )
)
